(kicad_pcb
	(version 20260206)
	(generator "pcbnew")
	(generator_version "10.0")
	(general
		(thickness 1.6)
		(legacy_teardrops no)
	)
	(paper "A4")
	(title_block
		(title "03242023_DA0F0TMBIJ0_F0T_Motherboard_J_brd_V01_OCP.brd")
		(comment 1 "Grand Teton / footprints 1807-1813 of 6105")
	)
	(layers
		(0 "F.Cu" signal "TOP")
		(4 "In1.Cu" signal "GND")
		(6 "In2.Cu" signal "IN1")
		(8 "In3.Cu" signal "GND1")
		(10 "In4.Cu" signal "IN2")
		(12 "In5.Cu" signal "GND2")
		(14 "In6.Cu" signal "IN3")
		(16 "In7.Cu" signal "GND3")
		(18 "In8.Cu" signal "VCC")
		(20 "In9.Cu" signal "VCC1")
		(22 "In10.Cu" signal "GND4")
		(24 "In11.Cu" signal "IN4")
		(26 "In12.Cu" signal "GND5")
		(28 "In13.Cu" signal "IN5")
		(30 "In14.Cu" signal "GND6")
		(32 "In15.Cu" signal "IN6")
		(34 "In16.Cu" signal "GND7")
		(2 "B.Cu" signal "BOTTOM")
		(9 "F.Adhes" user "F.Adhesive")
		(11 "B.Adhes" user "B.Adhesive")
		(13 "F.Paste" user "Package Geometry/Pastemask Top")
		(15 "B.Paste" user "Package Geometry/Pastemask Bottom")
		(5 "F.SilkS" user "Ref Des/Silkscreen Top")
		(7 "B.SilkS" user "Ref Des/Silkscreen Bottom")
		(1 "F.Mask" user "Board Geometry/Soldermask Top")
		(3 "B.Mask" user "Board Geometry/Soldermask Bottom")
		(17 "Dwgs.User" user "User.Drawings")
		(19 "Cmts.User" user "User.Comments")
		(21 "Eco1.User" user "User.Eco1")
		(23 "Eco2.User" user "User.Eco2")
		(25 "Edge.Cuts" user "Board Geometry/Outline")
		(27 "Margin" user)
		(31 "F.CrtYd" user "Package Geometry/Place Bound Top")
		(29 "B.CrtYd" user "Package Geometry/Place Bound Bottom")
		(35 "F.Fab" user "Ref Des/Assembly Top")
		(33 "B.Fab" user "Ref Des/Assembly Bottom")
	)
	(footprint ""
		(layer "F.Cu")
		(at 148.13788 -57.241948)
		(property "Reference" "R1703"
			(at 0 0 0)
			(layer "F.SilkS")
			(hide yes)
			(effects
				(font
					(size 1.27 1.27)
				)
			)
		)
		(property "Value" ""
			(at 0 0 0)
			(layer "F.Fab")
			(effects
				(font
					(size 1.27 1.27)
				)
			)
		)
		(duplicate_pad_numbers_are_jumpers no)
		(fp_line
			(start -0.7874 -0.4064)
			(end 0.7874 -0.4064)
			(stroke
				(width 0.1524)
				(type default)
			)
			(layer "F.SilkS")
		)
		(fp_line
			(start -0.7874 0.4064)
			(end -0.7874 -0.4064)
			(stroke
				(width 0.1524)
				(type default)
			)
			(layer "F.SilkS")
		)
		(fp_line
			(start 0.7874 -0.4064)
			(end 0.7874 0.4064)
			(stroke
				(width 0.1524)
				(type default)
			)
			(layer "F.SilkS")
		)
		(fp_line
			(start 0.7874 0.4064)
			(end -0.7874 0.4064)
			(stroke
				(width 0.1524)
				(type default)
			)
			(layer "F.SilkS")
		)
		(fp_line
			(start -0.67945 -0.305054)
			(end -0.12065 -0.305054)
			(stroke
				(width 0.1)
				(type default)
			)
			(layer "F.Fab")
		)
		(fp_line
			(start -0.67945 0.3048)
			(end -0.67945 -0.305054)
			(stroke
				(width 0.1)
				(type default)
			)
			(layer "F.Fab")
		)
		(fp_line
			(start -0.12065 -0.305054)
			(end -0.12065 -0.2794)
			(stroke
				(width 0.1)
				(type default)
			)
			(layer "F.Fab")
		)
		(fp_line
			(start -0.12065 -0.2794)
			(end 0.12065 -0.2794)
			(stroke
				(width 0.1)
				(type default)
			)
			(layer "F.Fab")
		)
		(fp_line
			(start -0.12065 0.2794)
			(end -0.12065 0.3048)
			(stroke
				(width 0.1)
				(type default)
			)
			(layer "F.Fab")
		)
		(fp_line
			(start -0.12065 0.3048)
			(end -0.67945 0.3048)
			(stroke
				(width 0.1)
				(type default)
			)
			(layer "F.Fab")
		)
		(fp_line
			(start 0.120396 0.2794)
			(end -0.12065 0.2794)
			(stroke
				(width 0.1)
				(type default)
			)
			(layer "F.Fab")
		)
		(fp_line
			(start 0.120396 0.3048)
			(end 0.120396 0.2794)
			(stroke
				(width 0.1)
				(type default)
			)
			(layer "F.Fab")
		)
		(fp_line
			(start 0.12065 -0.3048)
			(end 0.67945 -0.3048)
			(stroke
				(width 0.1)
				(type default)
			)
			(layer "F.Fab")
		)
		(fp_line
			(start 0.12065 -0.2794)
			(end 0.12065 -0.3048)
			(stroke
				(width 0.1)
				(type default)
			)
			(layer "F.Fab")
		)
		(fp_line
			(start 0.67945 -0.3048)
			(end 0.67945 0.3048)
			(stroke
				(width 0.1)
				(type default)
			)
			(layer "F.Fab")
		)
		(fp_line
			(start 0.67945 0.3048)
			(end 0.120396 0.3048)
			(stroke
				(width 0.1)
				(type default)
			)
			(layer "F.Fab")
		)
		(pad "1" smd circle
			(at -0.40005 0)
			(size 0 0)
			(layers "F.Cu" "F.Mask" "F.Paste")
			(net "P1V8_PCH_AUX")
		)
		(pad "2" smd circle
			(at 0.40005 0)
			(size 0 0)
			(layers "F.Cu" "F.Mask" "F.Paste")
			(net "SMB_M2_P0_1V8AUX_SCL_R")
		)
	)
	(footprint ""
		(layer "F.Cu")
		(at 32.761428 -102.761034)
		(property "Reference" "R2900"
			(at 0 0 0)
			(layer "F.SilkS")
			(hide yes)
			(effects
				(font
					(size 1.27 1.27)
				)
			)
		)
		(property "Value" ""
			(at 0 0 0)
			(layer "F.Fab")
			(effects
				(font
					(size 1.27 1.27)
				)
			)
		)
		(duplicate_pad_numbers_are_jumpers no)
		(fp_line
			(start -0.7874 -0.4064)
			(end 0.7874 -0.4064)
			(stroke
				(width 0.1524)
				(type default)
			)
			(layer "F.SilkS")
		)
		(fp_line
			(start -0.7874 0.4064)
			(end -0.7874 -0.4064)
			(stroke
				(width 0.1524)
				(type default)
			)
			(layer "F.SilkS")
		)
		(fp_line
			(start 0.7874 -0.4064)
			(end 0.7874 0.4064)
			(stroke
				(width 0.1524)
				(type default)
			)
			(layer "F.SilkS")
		)
		(fp_line
			(start 0.7874 0.4064)
			(end -0.7874 0.4064)
			(stroke
				(width 0.1524)
				(type default)
			)
			(layer "F.SilkS")
		)
		(fp_line
			(start -0.67945 -0.305054)
			(end -0.12065 -0.305054)
			(stroke
				(width 0.1)
				(type default)
			)
			(layer "F.Fab")
		)
		(fp_line
			(start -0.67945 0.3048)
			(end -0.67945 -0.305054)
			(stroke
				(width 0.1)
				(type default)
			)
			(layer "F.Fab")
		)
		(fp_line
			(start -0.12065 -0.305054)
			(end -0.12065 -0.2794)
			(stroke
				(width 0.1)
				(type default)
			)
			(layer "F.Fab")
		)
		(fp_line
			(start -0.12065 -0.2794)
			(end 0.12065 -0.2794)
			(stroke
				(width 0.1)
				(type default)
			)
			(layer "F.Fab")
		)
		(fp_line
			(start -0.12065 0.2794)
			(end -0.12065 0.3048)
			(stroke
				(width 0.1)
				(type default)
			)
			(layer "F.Fab")
		)
		(fp_line
			(start -0.12065 0.3048)
			(end -0.67945 0.3048)
			(stroke
				(width 0.1)
				(type default)
			)
			(layer "F.Fab")
		)
		(fp_line
			(start 0.120396 0.2794)
			(end -0.12065 0.2794)
			(stroke
				(width 0.1)
				(type default)
			)
			(layer "F.Fab")
		)
		(fp_line
			(start 0.120396 0.3048)
			(end 0.120396 0.2794)
			(stroke
				(width 0.1)
				(type default)
			)
			(layer "F.Fab")
		)
		(fp_line
			(start 0.12065 -0.3048)
			(end 0.67945 -0.3048)
			(stroke
				(width 0.1)
				(type default)
			)
			(layer "F.Fab")
		)
		(fp_line
			(start 0.12065 -0.2794)
			(end 0.12065 -0.3048)
			(stroke
				(width 0.1)
				(type default)
			)
			(layer "F.Fab")
		)
		(fp_line
			(start 0.67945 -0.3048)
			(end 0.67945 0.3048)
			(stroke
				(width 0.1)
				(type default)
			)
			(layer "F.Fab")
		)
		(fp_line
			(start 0.67945 0.3048)
			(end 0.120396 0.3048)
			(stroke
				(width 0.1)
				(type default)
			)
			(layer "F.Fab")
		)
		(pad "1" smd circle
			(at -0.40005 0)
			(size 0 0)
			(layers "F.Cu" "F.Mask" "F.Paste")
			(net "MAX11617_VREF")
		)
		(pad "2" smd circle
			(at 0.40005 0)
			(size 0 0)
			(layers "F.Cu" "F.Mask" "F.Paste")
			(net "MAX11617_VREF_R")
		)
	)
	(footprint ""
		(layer "F.Cu")
		(at 407.35377 -408.517344 -90)
		(property "Reference" "C893"
			(at 0 0 270)
			(layer "F.SilkS")
			(hide yes)
			(effects
				(font
					(size 1.27 1.27)
				)
			)
		)
		(property "Value" ""
			(at 0 0 270)
			(layer "F.Fab")
			(effects
				(font
					(size 1.27 1.27)
				)
			)
		)
		(duplicate_pad_numbers_are_jumpers no)
		(fp_line
			(start -0.299974 0.150114)
			(end -0.299974 -0.150114)
			(stroke
				(width 0.1)
				(type default)
			)
			(layer "F.Fab")
		)
		(fp_line
			(start 0.299974 0.150114)
			(end -0.299974 0.150114)
			(stroke
				(width 0.1)
				(type default)
			)
			(layer "F.Fab")
		)
		(fp_line
			(start -0.299974 -0.150114)
			(end 0.299974 -0.150114)
			(stroke
				(width 0.1)
				(type default)
			)
			(layer "F.Fab")
		)
		(fp_line
			(start 0.299974 -0.150114)
			(end 0.299974 0.150114)
			(stroke
				(width 0.1)
				(type default)
			)
			(layer "F.Fab")
		)
		(pad "1" smd rect
			(at -0.2667 0 270)
			(size 0.3048 0.381)
			(layers "F.Cu" "F.Mask" "F.Paste")
			(net "P5E_CPU0_PE3_TX_C_DP<4>")
		)
		(pad "2" smd rect
			(at 0.2667 0 270)
			(size 0.3048 0.381)
			(layers "F.Cu" "F.Mask" "F.Paste")
			(net "P5E_CPU0_PE3_TX_DP<4>")
		)
	)
	(footprint ""
		(layer "F.Cu")
		(at 170.59402 -99.466908)
		(property "Reference" "R2661"
			(at 0 0 0)
			(layer "F.SilkS")
			(hide yes)
			(effects
				(font
					(size 1.27 1.27)
				)
			)
		)
		(property "Value" ""
			(at 0 0 0)
			(layer "F.Fab")
			(effects
				(font
					(size 1.27 1.27)
				)
			)
		)
		(duplicate_pad_numbers_are_jumpers no)
		(fp_line
			(start -0.7874 -0.4064)
			(end 0.7874 -0.4064)
			(stroke
				(width 0.1524)
				(type default)
			)
			(layer "F.SilkS")
		)
		(fp_line
			(start -0.7874 0.4064)
			(end -0.7874 -0.4064)
			(stroke
				(width 0.1524)
				(type default)
			)
			(layer "F.SilkS")
		)
		(fp_line
			(start 0.7874 -0.4064)
			(end 0.7874 0.4064)
			(stroke
				(width 0.1524)
				(type default)
			)
			(layer "F.SilkS")
		)
		(fp_line
			(start 0.7874 0.4064)
			(end -0.7874 0.4064)
			(stroke
				(width 0.1524)
				(type default)
			)
			(layer "F.SilkS")
		)
		(fp_line
			(start -0.67945 -0.305054)
			(end -0.12065 -0.305054)
			(stroke
				(width 0.1)
				(type default)
			)
			(layer "F.Fab")
		)
		(fp_line
			(start -0.67945 0.3048)
			(end -0.67945 -0.305054)
			(stroke
				(width 0.1)
				(type default)
			)
			(layer "F.Fab")
		)
		(fp_line
			(start -0.12065 -0.305054)
			(end -0.12065 -0.2794)
			(stroke
				(width 0.1)
				(type default)
			)
			(layer "F.Fab")
		)
		(fp_line
			(start -0.12065 -0.2794)
			(end 0.12065 -0.2794)
			(stroke
				(width 0.1)
				(type default)
			)
			(layer "F.Fab")
		)
		(fp_line
			(start -0.12065 0.2794)
			(end -0.12065 0.3048)
			(stroke
				(width 0.1)
				(type default)
			)
			(layer "F.Fab")
		)
		(fp_line
			(start -0.12065 0.3048)
			(end -0.67945 0.3048)
			(stroke
				(width 0.1)
				(type default)
			)
			(layer "F.Fab")
		)
		(fp_line
			(start 0.120396 0.2794)
			(end -0.12065 0.2794)
			(stroke
				(width 0.1)
				(type default)
			)
			(layer "F.Fab")
		)
		(fp_line
			(start 0.120396 0.3048)
			(end 0.120396 0.2794)
			(stroke
				(width 0.1)
				(type default)
			)
			(layer "F.Fab")
		)
		(fp_line
			(start 0.12065 -0.3048)
			(end 0.67945 -0.3048)
			(stroke
				(width 0.1)
				(type default)
			)
			(layer "F.Fab")
		)
		(fp_line
			(start 0.12065 -0.2794)
			(end 0.12065 -0.3048)
			(stroke
				(width 0.1)
				(type default)
			)
			(layer "F.Fab")
		)
		(fp_line
			(start 0.67945 -0.3048)
			(end 0.67945 0.3048)
			(stroke
				(width 0.1)
				(type default)
			)
			(layer "F.Fab")
		)
		(fp_line
			(start 0.67945 0.3048)
			(end 0.120396 0.3048)
			(stroke
				(width 0.1)
				(type default)
			)
			(layer "F.Fab")
		)
		(pad "1" smd circle
			(at -0.40005 0)
			(size 0 0)
			(layers "F.Cu" "F.Mask" "F.Paste")
			(net "FM_SWB_PWR_EN")
		)
		(pad "2" smd circle
			(at 0.40005 0)
			(size 0 0)
			(layers "F.Cu" "F.Mask" "F.Paste")
			(net "FM_SWB_PWR_EN_R")
		)
	)
	(footprint ""
		(layer "F.Cu")
		(at 47.678594 -356.02418 90)
		(property "Reference" "PC396"
			(at 0 0 90)
			(layer "F.SilkS")
			(hide yes)
			(effects
				(font
					(size 1.27 1.27)
				)
			)
		)
		(property "Value" ""
			(at 0 0 90)
			(layer "F.Fab")
			(effects
				(font
					(size 1.27 1.27)
				)
			)
		)
		(duplicate_pad_numbers_are_jumpers no)
		(fp_line
			(start 0.7874 -0.4064)
			(end 0.7874 0.4064)
			(stroke
				(width 0.1524)
				(type default)
			)
			(layer "F.SilkS")
		)
		(fp_line
			(start -0.7874 -0.4064)
			(end 0.7874 -0.4064)
			(stroke
				(width 0.1524)
				(type default)
			)
			(layer "F.SilkS")
		)
		(fp_line
			(start 0.7874 0.4064)
			(end -0.7874 0.4064)
			(stroke
				(width 0.1524)
				(type default)
			)
			(layer "F.SilkS")
		)
		(fp_line
			(start -0.7874 0.4064)
			(end -0.7874 -0.4064)
			(stroke
				(width 0.1524)
				(type default)
			)
			(layer "F.SilkS")
		)
		(fp_line
			(start -0.12065 -0.305054)
			(end -0.12065 -0.2794)
			(stroke
				(width 0.1)
				(type default)
			)
			(layer "F.Fab")
		)
		(fp_line
			(start -0.67945 -0.305054)
			(end -0.12065 -0.305054)
			(stroke
				(width 0.1)
				(type default)
			)
			(layer "F.Fab")
		)
		(fp_line
			(start 0.67945 -0.3048)
			(end 0.67945 0.3048)
			(stroke
				(width 0.1)
				(type default)
			)
			(layer "F.Fab")
		)
		(fp_line
			(start 0.12065 -0.3048)
			(end 0.67945 -0.3048)
			(stroke
				(width 0.1)
				(type default)
			)
			(layer "F.Fab")
		)
		(fp_line
			(start 0.12065 -0.2794)
			(end 0.12065 -0.3048)
			(stroke
				(width 0.1)
				(type default)
			)
			(layer "F.Fab")
		)
		(fp_line
			(start -0.12065 -0.2794)
			(end 0.12065 -0.2794)
			(stroke
				(width 0.1)
				(type default)
			)
			(layer "F.Fab")
		)
		(fp_line
			(start 0.120396 0.2794)
			(end -0.12065 0.2794)
			(stroke
				(width 0.1)
				(type default)
			)
			(layer "F.Fab")
		)
		(fp_line
			(start -0.12065 0.2794)
			(end -0.12065 0.3048)
			(stroke
				(width 0.1)
				(type default)
			)
			(layer "F.Fab")
		)
		(fp_line
			(start 0.67945 0.3048)
			(end 0.120396 0.3048)
			(stroke
				(width 0.1)
				(type default)
			)
			(layer "F.Fab")
		)
		(fp_line
			(start 0.120396 0.3048)
			(end 0.120396 0.2794)
			(stroke
				(width 0.1)
				(type default)
			)
			(layer "F.Fab")
		)
		(fp_line
			(start -0.12065 0.3048)
			(end -0.67945 0.3048)
			(stroke
				(width 0.1)
				(type default)
			)
			(layer "F.Fab")
		)
		(fp_line
			(start -0.67945 0.3048)
			(end -0.67945 -0.305054)
			(stroke
				(width 0.1)
				(type default)
			)
			(layer "F.Fab")
		)
		(pad "1" smd circle
			(at -0.40005 0 90)
			(size 0 0)
			(layers "F.Cu" "F.Mask" "F.Paste")
			(net "PVCCFA_EHV_FIVRA_CPU1_VDD2")
		)
		(pad "2" smd circle
			(at 0.40005 0 90)
			(size 0 0)
			(layers "F.Cu" "F.Mask" "F.Paste")
			(net "GND")
		)
	)
	(footprint ""
		(layer "F.Cu")
		(at 70.7136 -34.788348)
		(property "Reference" "R3569"
			(at 0 0 0)
			(layer "F.SilkS")
			(hide yes)
			(effects
				(font
					(size 1.27 1.27)
				)
			)
		)
		(property "Value" ""
			(at 0 0 0)
			(layer "F.Fab")
			(effects
				(font
					(size 1.27 1.27)
				)
			)
		)
		(duplicate_pad_numbers_are_jumpers no)
		(fp_line
			(start -0.7874 -0.4064)
			(end 0.7874 -0.4064)
			(stroke
				(width 0.1524)
				(type default)
			)
			(layer "F.SilkS")
		)
		(fp_line
			(start -0.7874 0.4064)
			(end -0.7874 -0.4064)
			(stroke
				(width 0.1524)
				(type default)
			)
			(layer "F.SilkS")
		)
		(fp_line
			(start 0.7874 -0.4064)
			(end 0.7874 0.4064)
			(stroke
				(width 0.1524)
				(type default)
			)
			(layer "F.SilkS")
		)
		(fp_line
			(start 0.7874 0.4064)
			(end -0.7874 0.4064)
			(stroke
				(width 0.1524)
				(type default)
			)
			(layer "F.SilkS")
		)
		(fp_line
			(start -0.67945 -0.305054)
			(end -0.12065 -0.305054)
			(stroke
				(width 0.1)
				(type default)
			)
			(layer "F.Fab")
		)
		(fp_line
			(start -0.67945 0.3048)
			(end -0.67945 -0.305054)
			(stroke
				(width 0.1)
				(type default)
			)
			(layer "F.Fab")
		)
		(fp_line
			(start -0.12065 -0.305054)
			(end -0.12065 -0.2794)
			(stroke
				(width 0.1)
				(type default)
			)
			(layer "F.Fab")
		)
		(fp_line
			(start -0.12065 -0.2794)
			(end 0.12065 -0.2794)
			(stroke
				(width 0.1)
				(type default)
			)
			(layer "F.Fab")
		)
		(fp_line
			(start -0.12065 0.2794)
			(end -0.12065 0.3048)
			(stroke
				(width 0.1)
				(type default)
			)
			(layer "F.Fab")
		)
		(fp_line
			(start -0.12065 0.3048)
			(end -0.67945 0.3048)
			(stroke
				(width 0.1)
				(type default)
			)
			(layer "F.Fab")
		)
		(fp_line
			(start 0.120396 0.2794)
			(end -0.12065 0.2794)
			(stroke
				(width 0.1)
				(type default)
			)
			(layer "F.Fab")
		)
		(fp_line
			(start 0.120396 0.3048)
			(end 0.120396 0.2794)
			(stroke
				(width 0.1)
				(type default)
			)
			(layer "F.Fab")
		)
		(fp_line
			(start 0.12065 -0.3048)
			(end 0.67945 -0.3048)
			(stroke
				(width 0.1)
				(type default)
			)
			(layer "F.Fab")
		)
		(fp_line
			(start 0.12065 -0.2794)
			(end 0.12065 -0.3048)
			(stroke
				(width 0.1)
				(type default)
			)
			(layer "F.Fab")
		)
		(fp_line
			(start 0.67945 -0.3048)
			(end 0.67945 0.3048)
			(stroke
				(width 0.1)
				(type default)
			)
			(layer "F.Fab")
		)
		(fp_line
			(start 0.67945 0.3048)
			(end 0.120396 0.3048)
			(stroke
				(width 0.1)
				(type default)
			)
			(layer "F.Fab")
		)
		(pad "1" smd circle
			(at -0.40005 0)
			(size 0 0)
			(layers "F.Cu" "F.Mask" "F.Paste")
			(net "SMB_INA230_3_3V3AUX_SDA_R")
		)
		(pad "2" smd circle
			(at 0.40005 0)
			(size 0 0)
			(layers "F.Cu" "F.Mask" "F.Paste")
			(net "SMB_INA230_3_3V3AUX_SDA_R1")
		)
	)
	(footprint ""
		(layer "F.Cu")
		(at 86.973918 -408.517344 -90)
		(property "Reference" "C685"
			(at 0 0 270)
			(layer "F.SilkS")
			(hide yes)
			(effects
				(font
					(size 1.27 1.27)
				)
			)
		)
		(property "Value" ""
			(at 0 0 270)
			(layer "F.Fab")
			(effects
				(font
					(size 1.27 1.27)
				)
			)
		)
		(duplicate_pad_numbers_are_jumpers no)
		(fp_line
			(start -0.299974 0.150114)
			(end -0.299974 -0.150114)
			(stroke
				(width 0.1)
				(type default)
			)
			(layer "F.Fab")
		)
		(fp_line
			(start 0.299974 0.150114)
			(end -0.299974 0.150114)
			(stroke
				(width 0.1)
				(type default)
			)
			(layer "F.Fab")
		)
		(fp_line
			(start -0.299974 -0.150114)
			(end 0.299974 -0.150114)
			(stroke
				(width 0.1)
				(type default)
			)
			(layer "F.Fab")
		)
		(fp_line
			(start 0.299974 -0.150114)
			(end 0.299974 0.150114)
			(stroke
				(width 0.1)
				(type default)
			)
			(layer "F.Fab")
		)
		(pad "1" smd rect
			(at -0.2667 0 270)
			(size 0.3048 0.381)
			(layers "F.Cu" "F.Mask" "F.Paste")
			(net "P5E_CPU1_PE4_TX_C_DP<12>")
		)
		(pad "2" smd rect
			(at 0.2667 0 270)
			(size 0.3048 0.381)
			(layers "F.Cu" "F.Mask" "F.Paste")
			(net "P5E_CPU1_PE4_TX_DP<12>")
		)
	)
)
